FILE_TYPE = MACRO_DRAWING;
SET COLOR_WIRE YELLOW;
SET COLOR_PROP ORANGE;
SET COLOR_DOT WHITE;
SET COLOR_ARC YELLOW;
SET COLOR_BODY GREEN;
SET COLOR_NOTE PURPLE;
SET PROP_DISPLAY VALUE;
SET PAGE_NUMBER P213;
FORCEADD QUANTA_TITLE_BLOCK_C..1
(0 0);
FORCEPROP 1 LAST CUSTOM_TXT_CDS <NAME_2>
J 0
(-3175 50);
FORCEPROP 1 LAST CUSTOM_TXT_CDS <NAME_1>
J 0
(-3175 175);
FORCEPROP 1 LAST CUSTOM_TXT_CDS <Q_NUMBER>
J 0
(-1403 103);
DISPLAY 1.212766 (-1403 103);
FORCEPROP 1 LAST CUSTOM_TXT_CDS <Q_PROJ>
J 0
(-2382 102);
DISPLAY 1.212766 (-2382 102);
FORCEPROP 1 LAST CUSTOM_TXT_CDS <Q_REV>
J 0
(-184 103);
DISPLAY 1.212766 (-184 103);
FORCEPROP 1 LAST CUSTOM_TXT_CDS <CON_LAST_MODIFIED>
J 0
(-1885 15);
DISPLAY 0.978723 (-1885 15);
FORCEPROP 1 LAST CUSTOM_TXT_CDS <CON_PAGE_NUM> OF <CON_TOTAL_PAGES>
J 0
(-446 18);
DISPLAY 0.978723 (-446 18);
FORCEPROP 1 LAST Q_TITLE Blank
J 0
(-9366 26);
DISPLAY 2.446809 (-9366 26);
PAINT GREEN (-9366 26);
FORCEPROP 2 LAST PAGE_BORDER TRUE
J 0
(-7890 5250);
DISPLAY 0.638298 (-7890 5250);
PAINT PINK (-7890 5250);
DISPLAY INVISIBLE (-7890 5250);
FORCEPROP 1 LAST CDS_LMAN_SYM_OUTLINE -9475,6775,100,-125
J 0
(0 0);
DISPLAY 0.468085 (0 0);
PAINT GREEN (0 0);
DISPLAY INVISIBLE (0 0);
FORCEPROP 2 LAST CDS_LIB pure_quanta
J 0
(0 0);
DISPLAY INVISIBLE (0 0);
FORCEPROP 2 LAST CDS_XR_PAGE_TITLE CR-232 : @T6G_MB_LIB.T6G(SCH_1):PAGE232
J 0
(-7890 5250);
DISPLAY 0.638298 (-7890 5250);
PAINT PINK (-7890 5250);
DISPLAY INVISIBLE (-7890 5250);
FORCEPROP 2 LAST CUSTOM_TXT_CDS <XR_PAGE_TITLE>
J 0
(-7890 5250);
DISPLAY 0.638298 (-7890 5250);
PAINT PINK (-7890 5250);
DISPLAY INVISIBLE (-7890 5250);
FORCEPROP 1 LAST COMMENT_BODY TRUE
J 0
(12 -13);
DISPLAY 0.978723 (12 -13);
PAINT GREEN (12 -13);
DISPLAY INVISIBLE (12 -13);
FORCEPROP 1 LAST Q_DEPT BU9
J 1
(-3763 49);
DISPLAY 1.957447 (-3763 49);
PAINT GREEN (-3763 49);
DISPLAY INVISIBLE (-3763 49);
FORCEPROP 0 LAST CDS_CON_LAST_MODIFIED Thu Aug 24 10:15:31 2023
J 0
(-1885 15);
DISPLAY INVISIBLE (-1885 15);
QUIT
